# T6G (Grand Teton) — schematic netlist excerpt (pin names and nets, part order shuffled) for the footprints in the layout excerpt that follows; sources: Cadence DE-HDL packaged netlist, KiCad conversion of 04192023_DAF0TMB3IC0_F0TG_MB_C_brd_V02_OCP.brd

R665  Q_RES  1K 1% CHIP  pkg 0402LF  page 364 : A = P3V3_AUX ; B = P0V9_RETIMER_CPU1_INALERT
R1194  Q_RES  200 1% CHIP  pkg 0402LF  page 85 : A = P3V3_AUX ; B = BMC_FPGA_LED2_R_N
C955  Q_CAP_DIFFBUS  DIFF BUS_0.22UF 6.3V 20% X6S  pkg C0201  page 63 : \1\ = P5E_CPU0_P1_TX_C_DP<5> ; \2\ = P5E_CPU0_P1_TX_DP<5>

(kicad_pcb
	(version 20260206)
	(generator "pcbnew")
	(generator_version "10.0")
	(general
		(thickness 1.6)
		(legacy_teardrops no)
	)
	(paper "A4")
	(title_block
		(title "04192023_DAF0TMB3IC0_F0TG_MB_C_brd_V02_OCP.brd")
		(comment 1 "Grand Teton / footprints 4376-4378 of 8354")
	)
	(layers
		(0 "F.Cu" signal "TOP")
		(4 "In1.Cu" signal "GND")
		(6 "In2.Cu" signal "IN1")
		(8 "In3.Cu" signal "GND1")
		(10 "In4.Cu" signal "IN2")
		(12 "In5.Cu" signal "GND2")
		(14 "In6.Cu" signal "IN3")
		(16 "In7.Cu" signal "GND3")
		(18 "In8.Cu" signal "VCC")
		(20 "In9.Cu" signal "VCC1")
		(22 "In10.Cu" signal "GND4")
		(24 "In11.Cu" signal "IN4")
		(26 "In12.Cu" signal "GND5")
		(28 "In13.Cu" signal "IN5")
		(30 "In14.Cu" signal "GND6")
		(32 "In15.Cu" signal "IN6")
		(34 "In16.Cu" signal "GND7")
		(2 "B.Cu" signal "BOTTOM")
		(9 "F.Adhes" user "F.Adhesive")
		(11 "B.Adhes" user "B.Adhesive")
		(13 "F.Paste" user "Package Geometry/Pastemask Top")
		(15 "B.Paste" user "Package Geometry/Pastemask Bottom")
		(5 "F.SilkS" user "Ref Des/Silkscreen Top")
		(7 "B.SilkS" user "Ref Des/Silkscreen Bottom")
		(1 "F.Mask" user "Board Geometry/Soldermask Top")
		(3 "B.Mask" user "Board Geometry/Soldermask Bottom")
		(17 "Dwgs.User" user "User.Drawings")
		(19 "Cmts.User" user "User.Comments")
		(21 "Eco1.User" user "User.Eco1")
		(23 "Eco2.User" user "User.Eco2")
		(25 "Edge.Cuts" user "Board Geometry/Outline")
		(27 "Margin" user)
		(31 "F.CrtYd" user "Package Geometry/Place Bound Top")
		(29 "B.CrtYd" user "Package Geometry/Place Bound Bottom")
		(35 "F.Fab" user "Ref Des/Assembly Top")
		(33 "B.Fab" user "Ref Des/Assembly Bottom")
	)
	(footprint ""
		(layer "F.Cu")
		(at 329.2348 -15.979394 -90)
		(property "Reference" "R1194"
			(at 0 0 270)
			(layer "F.SilkS")
			(hide yes)
			(effects
				(font
					(size 1.27 1.27)
				)
			)
		)
		(property "Value" ""
			(at 0 0 270)
			(layer "F.Fab")
			(effects
				(font
					(size 1.27 1.27)
				)
			)
		)
		(duplicate_pad_numbers_are_jumpers no)
		(fp_line
			(start -0.7874 0.4064)
			(end -0.7874 -0.4064)
			(stroke
				(width 0.1524)
				(type default)
			)
			(layer "F.SilkS")
		)
		(fp_line
			(start 0.7874 0.4064)
			(end -0.7874 0.4064)
			(stroke
				(width 0.1524)
				(type default)
			)
			(layer "F.SilkS")
		)
		(fp_line
			(start -0.7874 -0.4064)
			(end 0.7874 -0.4064)
			(stroke
				(width 0.1524)
				(type default)
			)
			(layer "F.SilkS")
		)
		(fp_line
			(start 0.7874 -0.4064)
			(end 0.7874 0.4064)
			(stroke
				(width 0.1524)
				(type default)
			)
			(layer "F.SilkS")
		)
		(fp_line
			(start -0.67945 0.3048)
			(end -0.67945 -0.305054)
			(stroke
				(width 0.1)
				(type default)
			)
			(layer "F.Fab")
		)
		(fp_line
			(start -0.12065 0.3048)
			(end -0.67945 0.3048)
			(stroke
				(width 0.1)
				(type default)
			)
			(layer "F.Fab")
		)
		(fp_line
			(start 0.120396 0.3048)
			(end 0.120396 0.2794)
			(stroke
				(width 0.1)
				(type default)
			)
			(layer "F.Fab")
		)
		(fp_line
			(start 0.67945 0.3048)
			(end 0.120396 0.3048)
			(stroke
				(width 0.1)
				(type default)
			)
			(layer "F.Fab")
		)
		(fp_line
			(start -0.12065 0.2794)
			(end -0.12065 0.3048)
			(stroke
				(width 0.1)
				(type default)
			)
			(layer "F.Fab")
		)
		(fp_line
			(start 0.120396 0.2794)
			(end -0.12065 0.2794)
			(stroke
				(width 0.1)
				(type default)
			)
			(layer "F.Fab")
		)
		(fp_line
			(start -0.12065 -0.2794)
			(end 0.12065 -0.2794)
			(stroke
				(width 0.1)
				(type default)
			)
			(layer "F.Fab")
		)
		(fp_line
			(start 0.12065 -0.2794)
			(end 0.12065 -0.3048)
			(stroke
				(width 0.1)
				(type default)
			)
			(layer "F.Fab")
		)
		(fp_line
			(start 0.12065 -0.3048)
			(end 0.67945 -0.3048)
			(stroke
				(width 0.1)
				(type default)
			)
			(layer "F.Fab")
		)
		(fp_line
			(start 0.67945 -0.3048)
			(end 0.67945 0.3048)
			(stroke
				(width 0.1)
				(type default)
			)
			(layer "F.Fab")
		)
		(fp_line
			(start -0.67945 -0.305054)
			(end -0.12065 -0.305054)
			(stroke
				(width 0.1)
				(type default)
			)
			(layer "F.Fab")
		)
		(fp_line
			(start -0.12065 -0.305054)
			(end -0.12065 -0.2794)
			(stroke
				(width 0.1)
				(type default)
			)
			(layer "F.Fab")
		)
		(pad "1" smd circle
			(at -0.40005 0 270)
			(size 0 0)
			(layers "F.Cu" "F.Mask" "F.Paste")
			(net "P3V3_AUX")
		)
		(pad "2" smd circle
			(at 0.40005 0 270)
			(size 0 0)
			(layers "F.Cu" "F.Mask" "F.Paste")
			(net "BMC_FPGA_LED2_R_N")
		)
	)
	(footprint ""
		(layer "F.Cu")
		(at 20.480782 -409.421584 180)
		(property "Reference" "R665"
			(at 0 0 180)
			(layer "F.SilkS")
			(hide yes)
			(effects
				(font
					(size 1.27 1.27)
				)
			)
		)
		(property "Value" ""
			(at 0 0 180)
			(layer "F.Fab")
			(effects
				(font
					(size 1.27 1.27)
				)
			)
		)
		(duplicate_pad_numbers_are_jumpers no)
		(fp_line
			(start 0.7874 0.4064)
			(end -0.7874 0.4064)
			(stroke
				(width 0.1524)
				(type default)
			)
			(layer "F.SilkS")
		)
		(fp_line
			(start 0.7874 -0.4064)
			(end 0.7874 0.4064)
			(stroke
				(width 0.1524)
				(type default)
			)
			(layer "F.SilkS")
		)
		(fp_line
			(start -0.7874 0.4064)
			(end -0.7874 -0.4064)
			(stroke
				(width 0.1524)
				(type default)
			)
			(layer "F.SilkS")
		)
		(fp_line
			(start -0.7874 -0.4064)
			(end 0.7874 -0.4064)
			(stroke
				(width 0.1524)
				(type default)
			)
			(layer "F.SilkS")
		)
		(fp_line
			(start 0.67945 0.3048)
			(end 0.120396 0.3048)
			(stroke
				(width 0.1)
				(type default)
			)
			(layer "F.Fab")
		)
		(fp_line
			(start 0.67945 -0.3048)
			(end 0.67945 0.3048)
			(stroke
				(width 0.1)
				(type default)
			)
			(layer "F.Fab")
		)
		(fp_line
			(start 0.12065 -0.2794)
			(end 0.12065 -0.3048)
			(stroke
				(width 0.1)
				(type default)
			)
			(layer "F.Fab")
		)
		(fp_line
			(start 0.12065 -0.3048)
			(end 0.67945 -0.3048)
			(stroke
				(width 0.1)
				(type default)
			)
			(layer "F.Fab")
		)
		(fp_line
			(start 0.120396 0.3048)
			(end 0.120396 0.2794)
			(stroke
				(width 0.1)
				(type default)
			)
			(layer "F.Fab")
		)
		(fp_line
			(start 0.120396 0.2794)
			(end -0.12065 0.2794)
			(stroke
				(width 0.1)
				(type default)
			)
			(layer "F.Fab")
		)
		(fp_line
			(start -0.12065 0.3048)
			(end -0.67945 0.3048)
			(stroke
				(width 0.1)
				(type default)
			)
			(layer "F.Fab")
		)
		(fp_line
			(start -0.12065 0.2794)
			(end -0.12065 0.3048)
			(stroke
				(width 0.1)
				(type default)
			)
			(layer "F.Fab")
		)
		(fp_line
			(start -0.12065 -0.2794)
			(end 0.12065 -0.2794)
			(stroke
				(width 0.1)
				(type default)
			)
			(layer "F.Fab")
		)
		(fp_line
			(start -0.12065 -0.305054)
			(end -0.12065 -0.2794)
			(stroke
				(width 0.1)
				(type default)
			)
			(layer "F.Fab")
		)
		(fp_line
			(start -0.67945 0.3048)
			(end -0.67945 -0.305054)
			(stroke
				(width 0.1)
				(type default)
			)
			(layer "F.Fab")
		)
		(fp_line
			(start -0.67945 -0.305054)
			(end -0.12065 -0.305054)
			(stroke
				(width 0.1)
				(type default)
			)
			(layer "F.Fab")
		)
		(pad "1" smd circle
			(at -0.40005 0 180)
			(size 0 0)
			(layers "F.Cu" "F.Mask" "F.Paste")
			(net "P3V3_AUX")
		)
		(pad "2" smd circle
			(at 0.40005 0 180)
			(size 0 0)
			(layers "F.Cu" "F.Mask" "F.Paste")
			(net "P0V9_RETIMER_CPU1_INALERT")
		)
	)
	(footprint ""
		(layer "F.Cu")
		(at 338.324444 -381.41783 -90)
		(property "Reference" "C955"
			(at 0 0 270)
			(layer "F.SilkS")
			(hide yes)
			(effects
				(font
					(size 1.27 1.27)
				)
			)
		)
		(property "Value" ""
			(at 0 0 270)
			(layer "F.Fab")
			(effects
				(font
					(size 1.27 1.27)
				)
			)
		)
		(duplicate_pad_numbers_are_jumpers no)
		(fp_line
			(start -0.299974 0.150114)
			(end -0.299974 -0.150114)
			(stroke
				(width 0.1)
				(type default)
			)
			(layer "F.Fab")
		)
		(fp_line
			(start 0.299974 0.150114)
			(end -0.299974 0.150114)
			(stroke
				(width 0.1)
				(type default)
			)
			(layer "F.Fab")
		)
		(fp_line
			(start -0.299974 -0.150114)
			(end 0.299974 -0.150114)
			(stroke
				(width 0.1)
				(type default)
			)
			(layer "F.Fab")
		)
		(fp_line
			(start 0.299974 -0.150114)
			(end 0.299974 0.150114)
			(stroke
				(width 0.1)
				(type default)
			)
			(layer "F.Fab")
		)
		(pad "1" smd rect
			(at -0.2667 0 270)
			(size 0.3048 0.381)
			(layers "F.Cu" "F.Mask" "F.Paste")
			(net "P5E_CPU0_P1_TX_C_DP<5>")
		)
		(pad "2" smd rect
			(at 0.2667 0 270)
			(size 0.3048 0.381)
			(layers "F.Cu" "F.Mask" "F.Paste")
			(net "P5E_CPU0_P1_TX_DP<5>")
		)
	)
)
